FILE_TYPE = CONNECTIVITY;
{Allegro Design Entry HDL 16.6-p007 (v16-6-112F) 10/10/2012}
"PAGE_NUMBER" = 250;
0"NC";
1"GND\g";
2"P3V3_STBY\g";
3"GND\g";
4"P3V3_STBY\g";
5"GND\g";
6"P3V3_STBY\g";
7"GND\g";
8"P3V3_STBY\g";
9"P3V3_STBY\g";
10"GND\g";
11"FM_OCP_MEZZA_PRES";
12"FM_OCP_MEZZA_PRES_N"CDS_PHYS_NET_NAME"FM_OCP_MEZZA_PRES_N";
13"FM_OCP_MEZZC_PRES_LVT3_BMC";
14"FM_OCP_MEZZC_PRES_1V05_PCH_N";
15"FM_OCP_MEZZB_PRES_1V05_PCH_N";
16"FM_OCP_MEZZC_PRES_N"CDS_PHYS_NET_NAME"FM_OCP_MEZZA_PRES_N_CONN";
17"FM_OCP_MEZZB_PRES_N"CDS_PHYS_NET_NAME"FM_OCP_MEZZB_PRES_N";
18"FM_OCP_MEZZB_PRES_LVT3_BMC";
%"FET_N_DUAL"
"5","(-6525,4125)","0","mstr_discrete","I12";
;
MATERIAL"FET"
PART_NUMBER"D24280-001"
VALUE"2N7002DW"
LOCATION"Q1W2"
CDS_SEC"2"
CDS_LOCATION"Q1W2"
BOM_COST"DEBUG"
ROOM"UART_MUX"
CDS_LIB"mstr_discrete"
PACK_TYPE"SMLF"
SEC"2"
SEC_TYPE"SMLF";
"GATE <SIZE -1..0>"
$PN"5"18;
"SOURCE <SIZE-1..0>"
$PN"4"1;
"DRAIN <SIZE -1..0>"
$PN"3"15;
%"GND"
"1","(-6525,3825)","0","mstr_symbols","I16";
;
VOLTAGE"0.0V"
SIZE"1B"
CDS_LIB"mstr_symbols"
BODY_TYPE"PLUMBING"
HDL_POWER"GND";
"A\NAC"1;
%"P3V3_STBY"
"1","(-8300,5725)","0","mstr_symbols","I17";
;
SIZE"1B"
VOLTAGE"3.3V"
CDS_LIB"mstr_symbols"
BODY_TYPE"PLUMBING"
HDL_POWER"P3V3_STBY";
"G\NAC"2;
%"1MR2F-L-GP"
"1","(-8300,5500)","0","w_hdl","I18";
;
RATED"1/16W"
TOLERANCE"1%"
VALUE"1MR2F-L-GP"
ATTRIBUTE"1MOHM"
PACK_SIZE"0402"
LOCATION"R1W1"
CDS_LMAN_SYM_OUTLINE"-50,75,50,-75"
CDS_LIB"w_hdl"
PART_NUMBER"64.10045.L1L"
PACK_TYPE"SMD-RG1"
CDS_LOCATION"R1W1"
$SEC"1"
CDS_SEC"1";
"2"
$PN"2"12;
"1"
$PN"1"2;
%"GND"
"1","(-7350,5075)","0","mstr_symbols","I19";
;
VOLTAGE"0.0V"
SIZE"1B"
CDS_LIB"mstr_symbols"
BODY_TYPE"PLUMBING"
HDL_POWER"GND";
"A\NAC"3;
%"1MR2F-L-GP"
"1","(-8725,2575)","0","w_hdl","I2";
;
LOCATION"R1W6"
TOLERANCE"1%"
PACK_SIZE"0402"
RATED"1/16W"
ATTRIBUTE"1MOHM"
VALUE"1MR2F-L-GP"
CDS_LMAN_SYM_OUTLINE"-50,75,50,-75"
CDS_LIB"w_hdl"
PART_NUMBER"64.10045.L1L"
PACK_TYPE"SMD-RG1"
$SEC"1"
CDS_SEC"1"
CDS_LOCATION"R1W6";
"2"
$PN"2"16;
"1"
$PN"1"8;
%"P3V3_STBY"
"1","(-7350,4900)","0","mstr_symbols","I21";
;
CDS_LIB"mstr_symbols"
SIZE"1B"
VOLTAGE"3.3V"
BODY_TYPE"PLUMBING"
HDL_POWER"P3V3_STBY";
"G\NAC"4;
%"RES"
"1","(-7350,4700)","1","mstr_discrete","I22";
;
WATTAGE"1/16W"
PART_NUMBER"G21796-016"
PACK_TYPE"0402"
MATERIAL"CHIP"
LOCATION"R1W4"
TOLERANCE"1%"
VALUE"10.0K"
CDS_SEC"1"
CDS_LOCATION"R1W4"
ROOM"SB"
CDS_LIB"mstr_discrete"
SEC"1"
SEC_TYPE"0402";
"B"
$PN"2"4;
"A"
$PN"1"18;
%"GND"
"1","(-7350,3950)","0","mstr_symbols","I23";
;
CDS_LIB"mstr_symbols"
SIZE"1B"
VOLTAGE"0.0V"
BODY_TYPE"PLUMBING"
HDL_POWER"GND";
"A\NAC"5;
%"FET_N_DUAL"
"5","(-7350,4250)","0","mstr_discrete","I24";
;
VALUE"2N7002DW"
MATERIAL"FET"
PART_NUMBER"D24280-001"
LOCATION"Q1W2"
CDS_SEC"1"
CDS_LOCATION"Q1W2"
SEC_TYPE"SMLF"
SEC"1"
PACK_TYPE"SMLF"
CDS_LIB"mstr_discrete"
BOM_COST"DEBUG"
ROOM"UART_MUX";
"GATE <SIZE -1..0>"
$PN"2"17;
"SOURCE <SIZE-1..0>"
$PN"1"5;
"DRAIN <SIZE -1..0>"
$PN"6"18;
%"P3V3_STBY"
"1","(-8300,4575)","0","mstr_symbols","I26";
;
SIZE"1B"
VOLTAGE"3.3V"
CDS_LIB"mstr_symbols"
BODY_TYPE"PLUMBING"
HDL_POWER"P3V3_STBY";
"G\NAC"6;
%"1MR2F-L-GP"
"1","(-8300,4350)","0","w_hdl","I27";
;
LOCATION"R1W3"
VALUE"1MR2F-L-GP"
ATTRIBUTE"1MOHM"
RATED"1/16W"
TOLERANCE"1%"
PACK_SIZE"0402"
CDS_SEC"1"
$SEC"1"
CDS_LOCATION"R1W3"
PACK_TYPE"SMD-RG1"
PART_NUMBER"64.10045.L1L"
CDS_LIB"w_hdl"
CDS_LMAN_SYM_OUTLINE"-50,75,50,-75";
"2"
$PN"2"17;
"1"
$PN"1"6;
%"FET_N"
"8","(-7350,5375)","0","mstr_discrete","I29";
;
CDS_SEC"1"
LOCATION"Q1W1"
VALUE"2N7002"
MATERIAL"FET"
PART_NUMBER"C79254-001"
CDS_LOCATION"Q1W1"
CDS_LIB"mstr_discrete"
SEC"1"
SEC_TYPE"SOT23LF"
ROOM"HOT_SWAP"
PACK_TYPE"SOT23LF";
"GATE"
$PN"1"12;
"DRN"
$PN"3"11;
"SRC"
$PN"2"3;
%"FET_N_DUAL"
"5","(-7700,2450)","0","mstr_discrete","I3";
;
PART_NUMBER"D24280-001"
MATERIAL"FET"
VALUE"2N7002DW"
LOCATION"Q1W4"
CDS_LOCATION"Q1W4"
CDS_SEC"1"
ROOM"UART_MUX"
BOM_COST"DEBUG"
CDS_LIB"mstr_discrete"
PACK_TYPE"SMLF"
SEC"1"
SEC_TYPE"SMLF";
"GATE <SIZE -1..0>"
$PN"2"16;
"SOURCE <SIZE-1..0>"
$PN"1"7;
"DRAIN <SIZE -1..0>"
$PN"6"13;
%"GND"
"1","(-7700,2150)","0","mstr_symbols","I4";
;
CDS_LIB"mstr_symbols"
SIZE"1B"
VOLTAGE"0.0V"
BODY_TYPE"PLUMBING"
HDL_POWER"GND";
"A\NAC"7;
%"P3V3_STBY"
"1","(-8725,2800)","0","mstr_symbols","I5";
;
SIZE"1B"
VOLTAGE"3.3V"
CDS_LIB"mstr_symbols"
BODY_TYPE"PLUMBING"
HDL_POWER"P3V3_STBY";
"G\NAC"8;
%"RES"
"1","(-7700,2900)","1","mstr_discrete","I6";
;
CDS_SEC"1"
PART_NUMBER"G21796-016"
PACK_TYPE"0402"
MATERIAL"CHIP"
LOCATION"R1W7"
WATTAGE"1/16W"
TOLERANCE"1%"
VALUE"10.0K"
SEC_TYPE"0402"
SEC"1"
CDS_LOCATION"R1W7"
ROOM"SB"
CDS_LIB"mstr_discrete";
"B"
$PN"2"9;
"A"
$PN"1"13;
%"P3V3_STBY"
"1","(-7700,3100)","0","mstr_symbols","I7";
;
CDS_LIB"mstr_symbols"
SIZE"1B"
VOLTAGE"3.3V"
BODY_TYPE"PLUMBING"
HDL_POWER"P3V3_STBY";
"G\NAC"9;
%"FET_N_DUAL"
"5","(-5925,2800)","0","mstr_discrete","I8";
;
LOCATION"Q1W4"
PART_NUMBER"D24280-001"
VALUE"2N7002DW"
MATERIAL"FET"
CDS_LOCATION"Q1W4"
CDS_SEC"2"
CDS_LIB"mstr_discrete"
ROOM"UART_MUX"
BOM_COST"DEBUG"
PACK_TYPE"SMLF"
SEC"2"
SEC_TYPE"SMLF";
"GATE <SIZE -1..0>"
$PN"5"13;
"SOURCE <SIZE-1..0>"
$PN"4"10;
"DRAIN <SIZE -1..0>"
$PN"3"14;
%"GND"
"1","(-5925,2500)","0","mstr_symbols","I9";
;
SIZE"1B"
VOLTAGE"0.0V"
CDS_LIB"mstr_symbols"
BODY_TYPE"PLUMBING"
HDL_POWER"GND";
"A\NAC"10;
END.
